(kicad_pcb
	(version 20240108)
	(generator "pcbnew")
	(generator_version "8.0")
	(general
		(thickness 1.62)
		(legacy_teardrops no)
	)
	(paper "A4")
	(title_block
		(title "Jetson Orin Baseboard")
		(date "2025-03-12")
		(rev "1.3.4")
		(company "Antmicro Ltd")
		(comment 1 "www.antmicro.com")
		(comment 9 "footprints 116-118 of 677")
	)
	(layers
		(0 "F.Cu" signal)
		(1 "In1.Cu" signal)
		(2 "In2.Cu" signal)
		(3 "In3.Cu" signal)
		(4 "In4.Cu" jumper)
		(5 "In5.Cu" signal)
		(6 "In6.Cu" signal)
		(31 "B.Cu" signal)
		(32 "B.Adhes" user "B.Adhesive")
		(33 "F.Adhes" user "F.Adhesive")
		(34 "B.Paste" user)
		(35 "F.Paste" user)
		(36 "B.SilkS" user "B.Silkscreen")
		(37 "F.SilkS" user "F.Silkscreen")
		(38 "B.Mask" user)
		(39 "F.Mask" user)
		(40 "Dwgs.User" user "User.Drawings")
		(41 "Cmts.User" user "User.Comments")
		(42 "Eco1.User" user "User.Eco1")
		(43 "Eco2.User" user "User.Eco2")
		(44 "Edge.Cuts" user)
		(45 "Margin" user)
		(46 "B.CrtYd" user "B.Courtyard")
		(47 "F.CrtYd" user "F.Courtyard")
		(48 "B.Fab" user)
		(49 "F.Fab" user)
	)
	(footprint "antmicro-footprints:SW_KMR211NGLFS_SMD"
		(layer "F.Cu")
		(at 83.9 125.9)
		(property "Reference" "S5"
			(at 0.55 -1.73 0)
			(layer "F.SilkS")
			(effects
				(font
					(size 0.7 0.7)
					(thickness 0.15)
				)
				(justify left bottom)
			)
		)
		(property "Value" "SW_KMR211NGLFS_SMD"
			(at -3 3 0)
			(layer "F.Fab")
			(effects
				(font
					(size 0.7 0.7)
					(thickness 0.15)
				)
				(justify left bottom)
			)
		)
		(property "Footprint" "antmicro-footprints:SW_KMR211NGLFS_SMD"
			(at 0 0 0)
			(layer "F.Fab")
			(hide yes)
			(effects
				(font
					(size 1.27 1.27)
					(thickness 0.15)
				)
			)
		)
		(property "Datasheet" "http://www.farnell.com/datasheets/2631211.pdf"
			(at 0 0 0)
			(layer "F.Fab")
			(hide yes)
			(effects
				(font
					(size 1.27 1.27)
					(thickness 0.15)
				)
			)
		)
		(property "Author" "Antmicro"
			(at 0 0 0)
			(layer "F.Fab")
			(hide yes)
			(effects
				(font
					(size 1 1)
					(thickness 0.15)
				)
			)
		)
		(property "License" "Apache-2.0"
			(at 0 0 0)
			(layer "F.Fab")
			(hide yes)
			(effects
				(font
					(size 1 1)
					(thickness 0.15)
				)
			)
		)
		(property "MPN" "KMR211NGLFS"
			(at 0 0 0)
			(layer "F.Fab")
			(hide yes)
			(effects
				(font
					(size 1 1)
					(thickness 0.15)
				)
			)
		)
		(property "Manufacturer" "C&K"
			(at 0 0 0)
			(layer "F.Fab")
			(hide yes)
			(effects
				(font
					(size 1 1)
					(thickness 0.15)
				)
			)
		)
		(sheetname "Supply")
		(sheetfile "supply.kicad_sch")
		(attr smd)
		(fp_line
			(start -2.1 -1.6)
			(end -2.1 -1.499)
			(stroke
				(width 0.15)
				(type solid)
			)
			(layer "F.SilkS")
		)
		(fp_line
			(start -2.1 1.601)
			(end -2.1 1.48)
			(stroke
				(width 0.15)
				(type solid)
			)
			(layer "F.SilkS")
		)
		(fp_line
			(start 2.101 -1.6)
			(end -2.1 -1.6)
			(stroke
				(width 0.15)
				(type solid)
			)
			(layer "F.SilkS")
		)
		(fp_line
			(start 2.101 -1.58)
			(end 2.101 -1.459)
			(stroke
				(width 0.15)
				(type solid)
			)
			(layer "F.SilkS")
		)
		(fp_line
			(start 2.101 1.601)
			(end -2.1 1.601)
			(stroke
				(width 0.15)
				(type solid)
			)
			(layer "F.SilkS")
		)
		(fp_line
			(start 2.101 1.601)
			(end 2.101 1.48)
			(stroke
				(width 0.15)
				(type solid)
			)
			(layer "F.SilkS")
		)
		(fp_rect
			(start 2.751 1.75)
			(end -2.748 -1.749)
			(stroke
				(width 0.05)
				(type solid)
			)
			(fill none)
			(layer "F.CrtYd")
		)
		(fp_line
			(start -2.1 -1.6)
			(end -2.1 1.601)
			(stroke
				(width 0.15)
				(type solid)
			)
			(layer "F.Fab")
		)
		(fp_line
			(start -2.1 1.601)
			(end 2.101 1.601)
			(stroke
				(width 0.15)
				(type solid)
			)
			(layer "F.Fab")
		)
		(fp_line
			(start -0.248 -0.8)
			(end 0.25 -0.8)
			(stroke
				(width 0.15)
				(type solid)
			)
			(layer "F.Fab")
		)
		(fp_line
			(start 0.25 0.802)
			(end -0.248 0.802)
			(stroke
				(width 0.15)
				(type solid)
			)
			(layer "F.Fab")
		)
		(fp_line
			(start 2.101 -1.6)
			(end -2.1 -1.6)
			(stroke
				(width 0.15)
				(type solid)
			)
			(layer "F.Fab")
		)
		(fp_line
			(start 2.101 1.601)
			(end 2.101 -1.6)
			(stroke
				(width 0.15)
				(type solid)
			)
			(layer "F.Fab")
		)
		(fp_arc
			(start -0.248 0.802)
			(mid -1.050001 0.001)
			(end -0.248 -0.8)
			(stroke
				(width 0.15)
				(type solid)
			)
			(layer "F.Fab")
		)
		(fp_arc
			(start 0.25 -0.8)
			(mid 1.051001 0.001)
			(end 0.25 0.802)
			(stroke
				(width 0.15)
				(type solid)
			)
			(layer "F.Fab")
		)
		(fp_text user "Author: Antmicro"
			(at -3 5.5 0)
			(layer "F.Fab")
			(hide yes)
			(effects
				(font
					(size 0.7 0.7)
					(thickness 0.15)
				)
				(justify left bottom)
			)
		)
		(fp_text user "${REFERENCE}"
			(at -3 4.25 0)
			(layer "F.Fab")
			(hide yes)
			(effects
				(font
					(size 0.7 0.7)
					(thickness 0.15)
				)
				(justify left bottom)
			)
		)
		(fp_text user "License: Apache-2.0"
			(at -3 6.75 0)
			(layer "F.Fab")
			(hide yes)
			(effects
				(font
					(size 0.7 0.7)
					(thickness 0.15)
				)
				(justify left bottom)
			)
		)
		(pad "1" smd rect
			(at -2.048 -0.8 180)
			(size 0.9 1)
			(layers "F.Cu" "F.Paste" "F.Mask")
			(net 117 "3V3_STDB")
			(pinfunction "1")
			(pintype "passive")
		)
		(pad "2" smd rect
			(at 2.05 -0.8 180)
			(size 0.9 1)
			(layers "F.Cu" "F.Paste" "F.Mask")
			(net 117 "3V3_STDB")
			(pinfunction "2")
			(pintype "passive")
		)
		(pad "3" smd rect
			(at -2.048 0.802 180)
			(size 0.9 1)
			(layers "F.Cu" "F.Paste" "F.Mask")
			(net 179 "Net-(D61-A)")
			(pinfunction "3")
			(pintype "passive")
		)
		(pad "4" smd rect
			(at 2.05 0.802 180)
			(size 0.9 1)
			(layers "F.Cu" "F.Paste" "F.Mask")
			(net 179 "Net-(D61-A)")
			(pinfunction "4")
			(pintype "passive")
		)
	)
	(footprint "antmicro-footprints:C_0402_1005Metric"
		(layer "F.Cu")
		(at 63.31 100.52 180)
		(descr "Capacitor SMD 0402")
		(tags "capacitor SMD 0402")
		(property "Reference" "C93"
			(at -5.84 -3.555 0)
			(layer "F.SilkS")
			(effects
				(font
					(size 0.7 0.7)
					(thickness 0.15)
				)
				(justify right bottom)
			)
		)
		(property "Value" "C_1u_0402"
			(at -1.022927 2.155213 0)
			(layer "F.Fab")
			(effects
				(font
					(size 0.7 0.7)
					(thickness 0.15)
				)
				(justify right bottom)
			)
		)
		(property "Footprint" "antmicro-footprints:C_0402_1005Metric"
			(at 0 0 180)
			(layer "F.Fab")
			(hide yes)
			(effects
				(font
					(size 1.27 1.27)
					(thickness 0.15)
				)
			)
		)
		(property "Datasheet" "https://product.tdk.com/en/search/capacitor/ceramic/mlcc/info?part_no=C1005X6S1A105K050BC"
			(at 0 0 180)
			(layer "F.Fab")
			(hide yes)
			(effects
				(font
					(size 1.27 1.27)
					(thickness 0.15)
				)
			)
		)
		(property "Author" "Antmicro"
			(at 126.62 201.04 0)
			(layer "F.Fab")
			(hide yes)
			(effects
				(font
					(size 1 1)
					(thickness 0.15)
				)
			)
		)
		(property "Dielectric" ""
			(at 126.62 201.04 0)
			(layer "F.Fab")
			(hide yes)
			(effects
				(font
					(size 1 1)
					(thickness 0.15)
				)
			)
		)
		(property "License" "Apache-2.0"
			(at 126.62 201.04 0)
			(layer "F.Fab")
			(hide yes)
			(effects
				(font
					(size 1 1)
					(thickness 0.15)
				)
			)
		)
		(property "MPN" "C1005X6S1A105K050BC"
			(at 126.62 201.04 0)
			(layer "F.Fab")
			(hide yes)
			(effects
				(font
					(size 1 1)
					(thickness 0.15)
				)
			)
		)
		(property "Manufacturer" "TDK"
			(at 126.62 201.04 0)
			(layer "F.Fab")
			(hide yes)
			(effects
				(font
					(size 1 1)
					(thickness 0.15)
				)
			)
		)
		(property "Val" "1u"
			(at 126.62 201.04 0)
			(layer "F.Fab")
			(hide yes)
			(effects
				(font
					(size 1 1)
					(thickness 0.15)
				)
			)
		)
		(property "Voltage" ""
			(at 126.62 201.04 0)
			(layer "F.Fab")
			(hide yes)
			(effects
				(font
					(size 1 1)
					(thickness 0.15)
				)
			)
		)
		(sheetname "Supply")
		(sheetfile "supply.kicad_sch")
		(attr smd)
		(fp_rect
			(start -0.925 -0.47)
			(end 0.925 0.47)
			(stroke
				(width 0.05)
				(type default)
			)
			(fill none)
			(layer "F.CrtYd")
		)
		(fp_line
			(start 0.504 0.248)
			(end -0.494 0.248)
			(stroke
				(width 0.15)
				(type solid)
			)
			(layer "F.Fab")
		)
		(fp_line
			(start 0.504 -0.25)
			(end 0.504 0.248)
			(stroke
				(width 0.15)
				(type solid)
			)
			(layer "F.Fab")
		)
		(fp_line
			(start -0.494 0.248)
			(end -0.494 -0.25)
			(stroke
				(width 0.15)
				(type solid)
			)
			(layer "F.Fab")
		)
		(fp_line
			(start -0.494 -0.25)
			(end 0.504 -0.25)
			(stroke
				(width 0.15)
				(type solid)
			)
			(layer "F.Fab")
		)
		(fp_text user "License: Apache-2.0"
			(at -0.939 5.799 0)
			(layer "F.Fab")
			(hide yes)
			(effects
				(font
					(size 0.7 0.7)
					(thickness 0.15)
				)
				(justify right bottom)
			)
		)
		(fp_text user "Author: Antmicro"
			(at -0.939 3.399 0)
			(layer "F.Fab")
			(hide yes)
			(effects
				(font
					(size 0.7 0.7)
					(thickness 0.15)
				)
				(justify right bottom)
			)
		)
		(fp_text user "${REFERENCE}"
			(at -0.939 4.599 0)
			(layer "F.Fab")
			(hide yes)
			(effects
				(font
					(size 0.7 0.7)
					(thickness 0.15)
				)
				(justify right bottom)
			)
		)
		(pad "1" smd roundrect
			(at -0.48 0 180)
			(size 0.59 0.64)
			(layers "F.Cu" "F.Paste" "F.Mask")
			(roundrect_rratio 0.25)
			(net 1 "GND")
			(pintype "passive")
		)
		(pad "2" smd roundrect
			(at 0.48 0 180)
			(size 0.59 0.64)
			(layers "F.Cu" "F.Paste" "F.Mask")
			(roundrect_rratio 0.25)
			(net 759 "/Supply/5V_VDD")
			(pintype "passive")
		)
	)
	(footprint "antmicro-footprints:LED_0603_1608Metric_G"
		(layer "F.Cu")
		(at 130.55 101.95 -90)
		(descr "LED SMD 0603 Green")
		(tags "LED SMD 0603 Green")
		(property "Reference" "D52"
			(at -3.4 -0.45 90)
			(layer "F.SilkS")
			(effects
				(font
					(size 0.7 0.7)
					(thickness 0.15)
				)
				(justify right bottom)
			)
		)
		(property "Value" "LED_G_0603_LTST-C190GKT"
			(at -0.001 1.599 90)
			(layer "F.Fab")
			(effects
				(font
					(size 0.7 0.7)
					(thickness 0.15)
				)
				(justify right bottom)
			)
		)
		(property "Footprint" "antmicro-footprints:LED_0603_1608Metric_G"
			(at 0 0 -90)
			(layer "F.Fab")
			(hide yes)
			(effects
				(font
					(size 1.27 1.27)
					(thickness 0.15)
				)
			)
		)
		(property "Datasheet" "https://media.digikey.com/pdf/Data%20Sheets/Lite-On%20PDFs/LTST-C190GKT.pdf"
			(at 0 0 -90)
			(layer "F.Fab")
			(hide yes)
			(effects
				(font
					(size 1.27 1.27)
					(thickness 0.15)
				)
			)
		)
		(property "Author" "Antmicro"
			(at 28.6 232.5 0)
			(layer "F.Fab")
			(hide yes)
			(effects
				(font
					(size 1 1)
					(thickness 0.15)
				)
			)
		)
		(property "Color" "Green"
			(at 28.6 232.5 0)
			(layer "F.Fab")
			(hide yes)
			(effects
				(font
					(size 1 1)
					(thickness 0.15)
				)
			)
		)
		(property "License" "Apache-2.0"
			(at 28.6 232.5 0)
			(layer "F.Fab")
			(hide yes)
			(effects
				(font
					(size 1 1)
					(thickness 0.15)
				)
			)
		)
		(property "MPN" "LTST-C190GKT"
			(at 28.6 232.5 0)
			(layer "F.Fab")
			(hide yes)
			(effects
				(font
					(size 1 1)
					(thickness 0.15)
				)
			)
		)
		(property "Manufacturer" "Lite-On"
			(at 28.6 232.5 0)
			(layer "F.Fab")
			(hide yes)
			(effects
				(font
					(size 1 1)
					(thickness 0.15)
				)
			)
		)
		(sheetname "M.2")
		(sheetfile "m-2.kicad_sch")
		(attr smd)
		(fp_line
			(start 0.22 0.35)
			(end -0.22 0.35)
			(stroke
				(width 0.15)
				(type solid)
			)
			(layer "F.SilkS")
		)
		(fp_line
			(start -0.094672 0.201008)
			(end -0.094672 -0.198992)
			(stroke
				(width 0.1)
				(type solid)
			)
			(layer "F.SilkS")
		)
		(fp_line
			(start 0.105328 0.201008)
			(end -0.094672 0.001008)
			(stroke
				(width 0.1)
				(type solid)
			)
			(layer "F.SilkS")
		)
		(fp_line
			(start 0.105328 0.201008)
			(end 0.105328 -0.198992)
			(stroke
				(width 0.1)
				(type solid)
			)
			(layer "F.SilkS")
		)
		(fp_line
			(start -0.094672 0.001008)
			(end -0.24 0.001008)
			(stroke
				(width 0.1)
				(type solid)
			)
			(layer "F.SilkS")
		)
		(fp_line
			(start -0.094672 0.001008)
			(end 0.105328 -0.198992)
			(stroke
				(width 0.1)
				(type solid)
			)
			(layer "F.SilkS")
		)
		(fp_line
			(start 0.105328 0.001008)
			(end 0.24 0.001)
			(stroke
				(width 0.1)
				(type solid)
			)
			(layer "F.SilkS")
		)
		(fp_line
			(start -1.18 -0.319)
			(end -1.18 0.321)
			(stroke
				(width 0.15)
				(type solid)
			)
			(layer "F.SilkS")
		)
		(fp_line
			(start 0.22 -0.35)
			(end -0.22 -0.35)
			(stroke
				(width 0.15)
				(type solid)
			)
			(layer "F.SilkS")
		)
		(fp_rect
			(start 1.25 0.65)
			(end -1.25 -0.65)
			(stroke
				(width 0.05)
				(type solid)
			)
			(fill none)
			(layer "F.CrtYd")
		)
		(fp_line
			(start -0.199 0.2)
			(end -0.199 0.1)
			(stroke
				(width 0.15)
				(type solid)
			)
			(layer "F.Fab")
		)
		(fp_line
			(start 0.201 0.2)
			(end 0.201 0)
			(stroke
				(width 0.15)
				(type solid)
			)
			(layer "F.Fab")
		)
		(fp_line
			(start -0.199 0)
			(end -0.597 0)
			(stroke
				(width 0.15)
				(type solid)
			)
			(layer "F.Fab")
		)
		(fp_line
			(start -0.101 0)
			(end 0.201 0.2)
			(stroke
				(width 0.15)
				(type solid)
			)
			(layer "F.Fab")
		)
		(fp_line
			(start 0.201 0)
			(end 0.201 -0.202)
			(stroke
				(width 0.15)
				(type solid)
			)
			(layer "F.Fab")
		)
		(fp_line
			(start 0.599 0)
			(end 0.201 0)
			(stroke
				(width 0.15)
				(type solid)
			)
			(layer "F.Fab")
		)
		(fp_line
			(start -0.199 -0.202)
			(end -0.199 0.1)
			(stroke
				(width 0.15)
				(type solid)
			)
			(layer "F.Fab")
		)
		(fp_line
			(start 0.201 -0.202)
			(end -0.101 0)
			(stroke
				(width 0.15)
				(type solid)
			)
			(layer "F.Fab")
		)
		(fp_rect
			(start 0.848 0.4)
			(end -0.85 -0.402)
			(stroke
				(width 0.15)
				(type solid)
			)
			(fill none)
			(layer "F.Fab")
		)
		(fp_text user "Author: Antmicro"
			(at -1.4224 4.799 90)
			(layer "F.Fab")
			(hide yes)
			(effects
				(font
					(size 0.7 0.7)
					(thickness 0.15)
				)
				(justify right bottom)
			)
		)
		(fp_text user "${REFERENCE}"
			(at -1.4224 5.999 90)
			(layer "F.Fab")
			(hide yes)
			(effects
				(font
					(size 0.7 0.7)
					(thickness 0.15)
				)
				(justify right bottom)
			)
		)
		(fp_text user "License: Apache-2.0"
			(at -1.4224 3.599 90)
			(layer "F.Fab")
			(hide yes)
			(effects
				(font
					(size 0.7 0.7)
					(thickness 0.15)
				)
				(justify right bottom)
			)
		)
		(pad "1" smd roundrect
			(at -0.7 0 90)
			(size 0.8 1)
			(layers "F.Cu" "F.Paste" "F.Mask")
			(roundrect_rratio 0.2)
			(net 652 "/M.2/~{LED2}")
			(pinfunction "C")
			(pintype "passive")
		)
		(pad "2" smd roundrect
			(at 0.7 0 90)
			(size 0.8 1)
			(layers "F.Cu" "F.Paste" "F.Mask")
			(roundrect_rratio 0.2)
			(net 653 "Net-(D52-A)")
			(pinfunction "A")
			(pintype "passive")
		)
	)
)
